(kicad_pcb
	(version 20260206)
	(generator "pcbnew")
	(generator_version "10.0")
	(general
		(thickness 1.6)
		(legacy_teardrops no)
	)
	(paper "A4")
	(title_block
		(title "timecard-production-celestica-r4006 — R4006-B0001-02_R01.brd")
		(comment 1 "Time Appliance Project (Time Card) / footprint 197 of 1113 (U24), pads 1-111 of 484")
	)
	(layers
		(0 "F.Cu" signal "TOP")
		(4 "In1.Cu" signal "L02_GND1")
		(6 "In2.Cu" signal "L03_SIG1")
		(8 "In3.Cu" signal "L04_GND2")
		(10 "In4.Cu" signal "L05_VCC1")
		(12 "In5.Cu" signal "L06_VCC2")
		(14 "In6.Cu" signal "L07_GND3")
		(16 "In7.Cu" signal "L08_SIG2")
		(18 "In8.Cu" signal "L09_GND4")
		(2 "B.Cu" signal "BOTTOM")
		(9 "F.Adhes" user "F.Adhesive")
		(11 "B.Adhes" user "B.Adhesive")
		(13 "F.Paste" user "Package Geometry/Pastemask Top")
		(15 "B.Paste" user "Package Geometry/Pastemask Bottom")
		(5 "F.SilkS" user "Ref Des/Silkscreen Top")
		(7 "B.SilkS" user "Ref Des/Silkscreen Bottom")
		(1 "F.Mask" user "Board Geometry/Soldermask Top")
		(3 "B.Mask" user "Board Geometry/Soldermask Bottom")
		(17 "Dwgs.User" user "User.Drawings")
		(19 "Cmts.User" user "User.Comments")
		(21 "Eco1.User" user "User.Eco1")
		(23 "Eco2.User" user "User.Eco2")
		(25 "Edge.Cuts" user "Board Geometry/Outline")
		(27 "Margin" user)
		(31 "F.CrtYd" user "Package Geometry/Place Bound Top")
		(29 "B.CrtYd" user "Package Geometry/Place Bound Bottom")
		(35 "F.Fab" user "Ref Des/Assembly Top")
		(33 "B.Fab" user "Ref Des/Assembly Bottom")
	)
	(footprint ""
		(layer "F.Cu")
		(at 109.347 -44.323 90)
		(property "Reference" "U24"
			(at 12.27963 3.683 0)
			(unlocked yes)
			(layer "F.SilkS")
			(effects
				(font
					(size 0.7874 0.5842)
					(thickness 0.1524)
				)
			)
		)
		(property "Value" ""
			(at 0 0 90)
			(layer "F.Fab")
			(effects
				(font
					(size 1.27 1.27)
				)
			)
		)
		(property "User Part Number" "PARTNUM*"
			(at 0 14.056868 90)
			(unlocked yes)
			(layer "Cmts.User")
			(hide yes)
			(effects
				(font
					(size 0.7874 0.5842)
					(thickness 0.1524)
				)
			)
		)
		(property "Device Type" "XC7A200T_2FBG484C_FBG484-G240-A"
			(at 0 12.863068 90)
			(unlocked yes)
			(layer "F.Fab")
			(hide yes)
			(effects
				(font
					(size 0.7874 0.5842)
					(thickness 0.1524)
				)
			)
		)
		(duplicate_pad_numbers_are_jumpers no)
		(pad "A1" smd circle
			(at -10.500106 -10.500106 90)
			(size 0.50038 0.50038)
			(layers "F.Cu" "F.Mask" "F.Paste")
			(net "Net_124")
		)
		(pad "A2" smd circle
			(at -9.500108 -10.500106 90)
			(size 0.50038 0.50038)
			(layers "F.Cu" "F.Mask" "F.Paste")
			(net "SG")
		)
		(pad "A3" smd circle
			(at -8.50011 -10.500106 90)
			(size 0.50038 0.50038)
			(layers "F.Cu" "F.Mask" "F.Paste")
			(net "SG")
		)
		(pad "A4" smd circle
			(at -7.499858 -10.500106 90)
			(size 0.50038 0.50038)
			(layers "F.Cu" "F.Mask" "F.Paste")
			(net "CPU_RX_PCIE_MGT0_TXN")
		)
		(pad "A5" smd circle
			(at -6.49986 -10.500106 90)
			(size 0.50038 0.50038)
			(layers "F.Cu" "F.Mask" "F.Paste")
			(net "SG")
		)
		(pad "A6" smd circle
			(at -5.499862 -10.500106 90)
			(size 0.50038 0.50038)
			(layers "F.Cu" "F.Mask" "F.Paste")
			(net "CPU_RX_PCIE_MGT2_TXN")
		)
		(pad "A7" smd circle
			(at -4.499864 -10.500106 90)
			(size 0.50038 0.50038)
			(layers "F.Cu" "F.Mask" "F.Paste")
			(net "SG")
		)
		(pad "A8" smd circle
			(at -3.499866 -10.500106 90)
			(size 0.50038 0.50038)
			(layers "F.Cu" "F.Mask" "F.Paste")
			(net "CPU_TX_PCIE_MGT_0_RXN")
		)
		(pad "A9" smd circle
			(at -2.499868 -10.500106 90)
			(size 0.50038 0.50038)
			(layers "F.Cu" "F.Mask" "F.Paste")
			(net "SG")
		)
		(pad "A10" smd circle
			(at -1.49987 -10.500106 90)
			(size 0.50038 0.50038)
			(layers "F.Cu" "F.Mask" "F.Paste")
			(net "CPU_TX_PCIE_MGT_2_RXN")
		)
		(pad "A11" smd circle
			(at -0.499872 -10.500106 90)
			(size 0.50038 0.50038)
			(layers "F.Cu" "F.Mask" "F.Paste")
			(net "SG")
		)
		(pad "A12" smd circle
			(at 0.500126 -10.500106 90)
			(size 0.50038 0.50038)
			(layers "F.Cu" "F.Mask" "F.Paste")
			(net "SG")
		)
		(pad "A13" smd circle
			(at 1.500124 -10.500106 90)
			(size 0.50038 0.50038)
			(layers "F.Cu" "F.Mask" "F.Paste")
			(net "FPGA_USR_LED1")
		)
		(pad "A14" smd circle
			(at 2.500122 -10.500106 90)
			(size 0.50038 0.50038)
			(layers "F.Cu" "F.Mask" "F.Paste")
			(net "FPGA_USR_LED0")
		)
		(pad "A15" smd circle
			(at 3.50012 -10.500106 90)
			(size 0.50038 0.50038)
			(layers "F.Cu" "F.Mask" "F.Paste")
			(net "Net_85")
		)
		(pad "A16" smd circle
			(at 4.500118 -10.500106 90)
			(size 0.50038 0.50038)
			(layers "F.Cu" "F.Mask" "F.Paste")
			(net "Net_83")
		)
		(pad "A17" smd circle
			(at 5.500116 -10.500106 90)
			(size 0.50038 0.50038)
			(layers "F.Cu" "F.Mask" "F.Paste")
			(net "XP3R3V_FPGA")
		)
		(pad "A18" smd circle
			(at 6.500114 -10.500106 90)
			(size 0.50038 0.50038)
			(layers "F.Cu" "F.Mask" "F.Paste")
			(net "FPGA_OUT_GPS_LED_RED_N")
		)
		(pad "A19" smd circle
			(at 7.500112 -10.500106 90)
			(size 0.50038 0.50038)
			(layers "F.Cu" "F.Mask" "F.Paste")
			(net "Net_48")
		)
		(pad "A20" smd circle
			(at 8.50011 -10.500106 90)
			(size 0.50038 0.50038)
			(layers "F.Cu" "F.Mask" "F.Paste")
			(net "FPGA_OUT_GPS_LED_GREEN_N")
		)
		(pad "A21" smd circle
			(at 9.500108 -10.500106 90)
			(size 0.50038 0.50038)
			(layers "F.Cu" "F.Mask" "F.Paste")
			(net "IO_L21N_16")
		)
		(pad "A22" smd circle
			(at 10.500106 -10.500106 90)
			(size 0.50038 0.50038)
			(layers "F.Cu" "F.Mask" "F.Paste")
			(net "SG")
		)
		(pad "AA1" smd circle
			(at -10.500106 9.500108 90)
			(size 0.50038 0.50038)
			(layers "F.Cu" "F.Mask" "F.Paste")
			(net "Net_154")
		)
		(pad "AA2" smd circle
			(at -9.500108 9.500108 90)
			(size 0.50038 0.50038)
			(layers "F.Cu" "F.Mask" "F.Paste")
			(net "SG")
		)
		(pad "AA3" smd circle
			(at -8.50011 9.500108 90)
			(size 0.50038 0.50038)
			(layers "F.Cu" "F.Mask" "F.Paste")
			(net "Net_158")
		)
		(pad "AA4" smd circle
			(at -7.499858 9.500108 90)
			(size 0.50038 0.50038)
			(layers "F.Cu" "F.Mask" "F.Paste")
			(net "Net_94")
		)
		(pad "AA5" smd circle
			(at -6.49986 9.500108 90)
			(size 0.50038 0.50038)
			(layers "F.Cu" "F.Mask" "F.Paste")
			(net "FPGA_OUT_MAC_PPS_IN1P")
		)
		(pad "AA6" smd circle
			(at -5.499862 9.500108 90)
			(size 0.50038 0.50038)
			(layers "F.Cu" "F.Mask" "F.Paste")
			(net "Net_52")
		)
		(pad "AA7" smd circle
			(at -4.499864 9.500108 90)
			(size 0.50038 0.50038)
			(layers "F.Cu" "F.Mask" "F.Paste")
			(net "XP2R5V_FPGA")
		)
		(pad "AA8" smd circle
			(at -3.499866 9.500108 90)
			(size 0.50038 0.50038)
			(layers "F.Cu" "F.Mask" "F.Paste")
			(net "IO_L22P_34")
		)
		(pad "AA9" smd circle
			(at -2.499868 9.500108 90)
			(size 0.50038 0.50038)
			(layers "F.Cu" "F.Mask" "F.Paste")
			(net "FPGA_IN_MAC_BITEOUT")
		)
		(pad "AA10" smd circle
			(at -1.49987 9.500108 90)
			(size 0.50038 0.50038)
			(layers "F.Cu" "F.Mask" "F.Paste")
			(net "Net_177")
		)
		(pad "AA11" smd circle
			(at -0.499872 9.500108 90)
			(size 0.50038 0.50038)
			(layers "F.Cu" "F.Mask" "F.Paste")
			(net "Net_176")
		)
		(pad "AA12" smd circle
			(at 0.500126 9.500108 90)
			(size 0.50038 0.50038)
			(layers "F.Cu" "F.Mask" "F.Paste")
			(net "SG")
		)
		(pad "AA13" smd circle
			(at 1.500124 9.500108 90)
			(size 0.50038 0.50038)
			(layers "F.Cu" "F.Mask" "F.Paste")
			(net "FPGA_OUT_SN_EEPROM_WP")
		)
		(pad "AA14" smd circle
			(at 2.500122 9.500108 90)
			(size 0.50038 0.50038)
			(layers "F.Cu" "F.Mask" "F.Paste")
			(net "Net_140")
		)
		(pad "AA15" smd circle
			(at 3.50012 9.500108 90)
			(size 0.50038 0.50038)
			(layers "F.Cu" "F.Mask" "F.Paste")
			(net "FPGA_IO_FT_USBDET_RST_N")
		)
		(pad "AA16" smd circle
			(at 4.500118 9.500108 90)
			(size 0.50038 0.50038)
			(layers "F.Cu" "F.Mask" "F.Paste")
			(net "Net_60")
		)
		(pad "AA17" smd circle
			(at 5.500116 9.500108 90)
			(size 0.50038 0.50038)
			(layers "F.Cu" "F.Mask" "F.Paste")
			(net "XP3R3V_FPGA")
		)
		(pad "AA18" smd circle
			(at 6.500114 9.500108 90)
			(size 0.50038 0.50038)
			(layers "F.Cu" "F.Mask" "F.Paste")
			(net "UART_MAC_RX_FPGA_TX")
		)
		(pad "AA19" smd circle
			(at 7.500112 9.500108 90)
			(size 0.50038 0.50038)
			(layers "F.Cu" "F.Mask" "F.Paste")
			(net "Net_42")
		)
		(pad "AA20" smd circle
			(at 8.50011 9.500108 90)
			(size 0.50038 0.50038)
			(layers "F.Cu" "F.Mask" "F.Paste")
			(net "ANT2_IN")
		)
		(pad "AA21" smd circle
			(at 9.500108 9.500108 90)
			(size 0.50038 0.50038)
			(layers "F.Cu" "F.Mask" "F.Paste")
			(net "ANT1_IN")
		)
		(pad "AA22" smd circle
			(at 10.500106 9.500108 90)
			(size 0.50038 0.50038)
			(layers "F.Cu" "F.Mask" "F.Paste")
			(net "SG")
		)
		(pad "AB1" smd circle
			(at -10.500106 10.500106 90)
			(size 0.50038 0.50038)
			(layers "F.Cu" "F.Mask" "F.Paste")
			(net "Net_151")
		)
		(pad "AB2" smd circle
			(at -9.500108 10.500106 90)
			(size 0.50038 0.50038)
			(layers "F.Cu" "F.Mask" "F.Paste")
			(net "FPGA_OUT_MAC_PPS_IN0N")
		)
		(pad "AB3" smd circle
			(at -8.50011 10.500106 90)
			(size 0.50038 0.50038)
			(layers "F.Cu" "F.Mask" "F.Paste")
			(net "FPGA_OUT_MAC_PPS_IN0P")
		)
		(pad "AB4" smd circle
			(at -7.499858 10.500106 90)
			(size 0.50038 0.50038)
			(layers "F.Cu" "F.Mask" "F.Paste")
			(net "XP2R5V_FPGA")
		)
		(pad "AB5" smd circle
			(at -6.49986 10.500106 90)
			(size 0.50038 0.50038)
			(layers "F.Cu" "F.Mask" "F.Paste")
			(net "FPGA_OUT_MAC_PPS_IN1N")
		)
		(pad "AB6" smd circle
			(at -5.499862 10.500106 90)
			(size 0.50038 0.50038)
			(layers "F.Cu" "F.Mask" "F.Paste")
			(net "IO_L20N_34")
		)
		(pad "AB7" smd circle
			(at -4.499864 10.500106 90)
			(size 0.50038 0.50038)
			(layers "F.Cu" "F.Mask" "F.Paste")
			(net "IO_L20P_34")
		)
		(pad "AB8" smd circle
			(at -3.499866 10.500106 90)
			(size 0.50038 0.50038)
			(layers "F.Cu" "F.Mask" "F.Paste")
			(net "IO_L22N_34")
		)
		(pad "AB9" smd circle
			(at -2.499868 10.500106 90)
			(size 0.50038 0.50038)
			(layers "F.Cu" "F.Mask" "F.Paste")
			(net "SG")
		)
		(pad "AB10" smd circle
			(at -1.49987 10.500106 90)
			(size 0.50038 0.50038)
			(layers "F.Cu" "F.Mask" "F.Paste")
			(net "FPGA_IN_MAC_ALARM_OUT_N")
		)
		(pad "AB11" smd circle
			(at -0.499872 10.500106 90)
			(size 0.50038 0.50038)
			(layers "F.Cu" "F.Mask" "F.Paste")
			(net "Net_153")
		)
		(pad "AB12" smd circle
			(at 0.500126 10.500106 90)
			(size 0.50038 0.50038)
			(layers "F.Cu" "F.Mask" "F.Paste")
			(net "Net_150")
		)
		(pad "AB13" smd circle
			(at 1.500124 10.500106 90)
			(size 0.50038 0.50038)
			(layers "F.Cu" "F.Mask" "F.Paste")
			(net "FPGA_OUT_SEC_EEPROM_WP")
		)
		(pad "AB14" smd circle
			(at 2.500122 10.500106 90)
			(size 0.50038 0.50038)
			(layers "F.Cu" "F.Mask" "F.Paste")
			(net "XP3R3V_FPGA")
		)
		(pad "AB15" smd circle
			(at 3.50012 10.500106 90)
			(size 0.50038 0.50038)
			(layers "F.Cu" "F.Mask" "F.Paste")
			(net "Net_71")
		)
		(pad "AB16" smd circle
			(at 4.500118 10.500106 90)
			(size 0.50038 0.50038)
			(layers "F.Cu" "F.Mask" "F.Paste")
			(net "FPGA_EEPROM_I2C_SCL")
		)
		(pad "AB17" smd circle
			(at 5.500116 10.500106 90)
			(size 0.50038 0.50038)
			(layers "F.Cu" "F.Mask" "F.Paste")
			(net "FPGA_EEPROM_I2C_SDA")
		)
		(pad "AB18" smd circle
			(at 6.500114 10.500106 90)
			(size 0.50038 0.50038)
			(layers "F.Cu" "F.Mask" "F.Paste")
			(net "UART_MAC_TX_FPGA_RX")
		)
		(pad "AB19" smd circle
			(at 7.500112 10.500106 90)
			(size 0.50038 0.50038)
			(layers "F.Cu" "F.Mask" "F.Paste")
			(net "SG")
		)
		(pad "AB20" smd circle
			(at 8.50011 10.500106 90)
			(size 0.50038 0.50038)
			(layers "F.Cu" "F.Mask" "F.Paste")
			(net "Net_39")
		)
		(pad "AB21" smd circle
			(at 9.500108 10.500106 90)
			(size 0.50038 0.50038)
			(layers "F.Cu" "F.Mask" "F.Paste")
			(net "Net_163")
		)
		(pad "AB22" smd circle
			(at 10.500106 10.500106 90)
			(size 0.50038 0.50038)
			(layers "F.Cu" "F.Mask" "F.Paste")
			(net "Net_162")
		)
		(pad "B1" smd circle
			(at -10.500106 -9.500108 90)
			(size 0.50038 0.50038)
			(layers "F.Cu" "F.Mask" "F.Paste")
			(net "Net_126")
		)
		(pad "B2" smd circle
			(at -9.500108 -9.500108 90)
			(size 0.50038 0.50038)
			(layers "F.Cu" "F.Mask" "F.Paste")
			(net "Net_129")
		)
		(pad "B3" smd circle
			(at -8.50011 -9.500108 90)
			(size 0.50038 0.50038)
			(layers "F.Cu" "F.Mask" "F.Paste")
			(net "SG")
		)
		(pad "B4" smd circle
			(at -7.499858 -9.500108 90)
			(size 0.50038 0.50038)
			(layers "F.Cu" "F.Mask" "F.Paste")
			(net "CPU_RX_PCIE_MGT0_TXP")
		)
		(pad "B5" smd circle
			(at -6.49986 -9.500108 90)
			(size 0.50038 0.50038)
			(layers "F.Cu" "F.Mask" "F.Paste")
			(net "FPGA_MGTAVTT")
		)
		(pad "B6" smd circle
			(at -5.499862 -9.500108 90)
			(size 0.50038 0.50038)
			(layers "F.Cu" "F.Mask" "F.Paste")
			(net "CPU_RX_PCIE_MGT2_TXP")
		)
		(pad "B7" smd circle
			(at -4.499864 -9.500108 90)
			(size 0.50038 0.50038)
			(layers "F.Cu" "F.Mask" "F.Paste")
			(net "FPGA_MGTAVTT")
		)
		(pad "B8" smd circle
			(at -3.499866 -9.500108 90)
			(size 0.50038 0.50038)
			(layers "F.Cu" "F.Mask" "F.Paste")
			(net "CPU_TX_PCIE_MGT_0_RXP")
		)
		(pad "B9" smd circle
			(at -2.499868 -9.500108 90)
			(size 0.50038 0.50038)
			(layers "F.Cu" "F.Mask" "F.Paste")
			(net "FPGA_MGTAVTT")
		)
		(pad "B10" smd circle
			(at -1.49987 -9.500108 90)
			(size 0.50038 0.50038)
			(layers "F.Cu" "F.Mask" "F.Paste")
			(net "CPU_TX_PCIE_MGT_2_RXP")
		)
		(pad "B11" smd circle
			(at -0.499872 -9.500108 90)
			(size 0.50038 0.50038)
			(layers "F.Cu" "F.Mask" "F.Paste")
			(net "FPGA_MGTAVTT")
		)
		(pad "B12" smd circle
			(at 0.500126 -9.500108 90)
			(size 0.50038 0.50038)
			(layers "F.Cu" "F.Mask" "F.Paste")
			(net "SG")
		)
		(pad "B13" smd circle
			(at 1.500124 -9.500108 90)
			(size 0.50038 0.50038)
			(layers "F.Cu" "F.Mask" "F.Paste")
			(net "LED_DATOUT0")
		)
		(pad "B14" smd circle
			(at 2.500122 -9.500108 90)
			(size 0.50038 0.50038)
			(layers "F.Cu" "F.Mask" "F.Paste")
			(net "XP3R3V_FPGA")
		)
		(pad "B15" smd circle
			(at 3.50012 -9.500108 90)
			(size 0.50038 0.50038)
			(layers "F.Cu" "F.Mask" "F.Paste")
			(net "Net_81")
		)
		(pad "B16" smd circle
			(at 4.500118 -9.500108 90)
			(size 0.50038 0.50038)
			(layers "F.Cu" "F.Mask" "F.Paste")
			(net "Net_80")
		)
		(pad "B17" smd circle
			(at 5.500116 -9.500108 90)
			(size 0.50038 0.50038)
			(layers "F.Cu" "F.Mask" "F.Paste")
			(net "Net_32")
		)
		(pad "B18" smd circle
			(at 6.500114 -9.500108 90)
			(size 0.50038 0.50038)
			(layers "F.Cu" "F.Mask" "F.Paste")
			(net "Net_31")
		)
		(pad "B19" smd circle
			(at 7.500112 -9.500108 90)
			(size 0.50038 0.50038)
			(layers "F.Cu" "F.Mask" "F.Paste")
			(net "SG")
		)
		(pad "B20" smd circle
			(at 8.50011 -9.500108 90)
			(size 0.50038 0.50038)
			(layers "F.Cu" "F.Mask" "F.Paste")
			(net "FPGA_OUT_GPS_LED_BLUE_N")
		)
		(pad "B21" smd circle
			(at 9.500108 -9.500108 90)
			(size 0.50038 0.50038)
			(layers "F.Cu" "F.Mask" "F.Paste")
			(net "IO_L21P_16")
		)
		(pad "B22" smd circle
			(at 10.500106 -9.500108 90)
			(size 0.50038 0.50038)
			(layers "F.Cu" "F.Mask" "F.Paste")
			(net "IO_L20N_16")
		)
		(pad "C1" smd circle
			(at -10.500106 -8.50011 90)
			(size 0.50038 0.50038)
			(layers "F.Cu" "F.Mask" "F.Paste")
			(net "XP2R5V_FPGA")
		)
		(pad "C2" smd circle
			(at -9.500108 -8.50011 90)
			(size 0.50038 0.50038)
			(layers "F.Cu" "F.Mask" "F.Paste")
			(net "Net_131")
		)
		(pad "C3" smd circle
			(at -8.50011 -8.50011 90)
			(size 0.50038 0.50038)
			(layers "F.Cu" "F.Mask" "F.Paste")
			(net "SG")
		)
		(pad "C4" smd circle
			(at -7.499858 -8.50011 90)
			(size 0.50038 0.50038)
			(layers "F.Cu" "F.Mask" "F.Paste")
			(net "FPGA_MGTAVTT")
		)
		(pad "C5" smd circle
			(at -6.49986 -8.50011 90)
			(size 0.50038 0.50038)
			(layers "F.Cu" "F.Mask" "F.Paste")
			(net "CPU_RX_PCIE_MGT1_TXN")
		)
		(pad "C6" smd circle
			(at -5.499862 -8.50011 90)
			(size 0.50038 0.50038)
			(layers "F.Cu" "F.Mask" "F.Paste")
			(net "SG")
		)
		(pad "C7" smd circle
			(at -4.499864 -8.50011 90)
			(size 0.50038 0.50038)
			(layers "F.Cu" "F.Mask" "F.Paste")
			(net "CPU_RX_PCIE_MGT3_TXN")
		)
		(pad "C8" smd circle
			(at -3.499866 -8.50011 90)
			(size 0.50038 0.50038)
			(layers "F.Cu" "F.Mask" "F.Paste")
			(net "FPGA_MGTAVTT")
		)
		(pad "C9" smd circle
			(at -2.499868 -8.50011 90)
			(size 0.50038 0.50038)
			(layers "F.Cu" "F.Mask" "F.Paste")
			(net "CPU_TX_PCIE_MGT_3_RXN")
		)
		(pad "C10" smd circle
			(at -1.49987 -8.50011 90)
			(size 0.50038 0.50038)
			(layers "F.Cu" "F.Mask" "F.Paste")
			(net "SG")
		)
		(pad "C11" smd circle
			(at -0.499872 -8.50011 90)
			(size 0.50038 0.50038)
			(layers "F.Cu" "F.Mask" "F.Paste")
			(net "CPU_TX_PCIE_MGT_1_RXN")
		)
		(pad "C12" smd circle
			(at 0.500126 -8.50011 90)
			(size 0.50038 0.50038)
			(layers "F.Cu" "F.Mask" "F.Paste")
			(net "SG")
		)
		(pad "C13" smd circle
			(at 1.500124 -8.50011 90)
			(size 0.50038 0.50038)
			(layers "F.Cu" "F.Mask" "F.Paste")
			(net "LED_DATOUT1")
		)
		(pad "C14" smd circle
			(at 2.500122 -8.50011 90)
			(size 0.50038 0.50038)
			(layers "F.Cu" "F.Mask" "F.Paste")
			(net "FPGA_OUT_SMA2_LED_BLUE_N")
		)
		(pad "C15" smd circle
			(at 3.50012 -8.50011 90)
			(size 0.50038 0.50038)
			(layers "F.Cu" "F.Mask" "F.Paste")
			(net "FPGA_OUT_SMA2_LED_GREEN_N")
		)
		(pad "C16" smd circle
			(at 4.500118 -8.50011 90)
			(size 0.50038 0.50038)
			(layers "F.Cu" "F.Mask" "F.Paste")
			(net "SG")
		)
		(pad "C17" smd circle
			(at 5.500116 -8.50011 90)
			(size 0.50038 0.50038)
			(layers "F.Cu" "F.Mask" "F.Paste")
			(net "FPGA_OUT_SMA3_LED_GREEN_N")
		)
		(pad "C18" smd circle
			(at 6.500114 -8.50011 90)
			(size 0.50038 0.50038)
			(layers "F.Cu" "F.Mask" "F.Paste")
			(net "FPGA_OUT_SMA3_LED_RED_N")
		)
		(pad "C19" smd circle
			(at 7.500112 -8.50011 90)
			(size 0.50038 0.50038)
			(layers "F.Cu" "F.Mask" "F.Paste")
			(net "Net_34")
		)
		(pad "C20" smd circle
			(at 8.50011 -8.50011 90)
			(size 0.50038 0.50038)
			(layers "F.Cu" "F.Mask" "F.Paste")
			(net "Net_56")
		)
		(pad "C21" smd circle
			(at 9.500108 -8.50011 90)
			(size 0.50038 0.50038)
			(layers "F.Cu" "F.Mask" "F.Paste")
			(net "XP3R3V_FPGA")
		)
		(pad "C22" smd circle
			(at 10.500106 -8.50011 90)
			(size 0.50038 0.50038)
			(layers "F.Cu" "F.Mask" "F.Paste")
			(net "IO_L20P_16")
		)
		(pad "D1" smd circle
			(at -10.500106 -7.499858 90)
			(size 0.50038 0.50038)
			(layers "F.Cu" "F.Mask" "F.Paste")
			(net "Net_133")
		)
	)
)
